FILE_TYPE = CONNECTIVITY;
{Allegro Design Entry HDL 16.6-p007 (v16-6-112F) 10/10/2012}
"PAGE_NUMBER" = 225;
0"NC";
1"PVDDQ_GHJ\g";
2"GND\g";
3"VR_FET_SW_P12V_STBY_PVDDQ_GHJ\g";
4"GND\g";
5"P12V_STBY\g";
6"GND\g";
7"PVDDQ_GHJ\g";
8"PVDDQ_GHJ\g";
9"GND\g";
10"PVDDQ_GHJ\g";
11"GND\g";
12"PVDDQ_GHJ\g";
13"GND\g";
14"PVDDQ_GHJ\g";
15"GND\g";
16"GND\g";
17"PVDDQ_GHJ\g";
18"PVDDQ_GHJ\g";
19"GND\g";
20"PVDDQ_GHJ\g";
21"GND\g";
22"VSENSE_PVDDQ_GHJ_N";
23"VSENSE_PVDDQ_GHJ_P";
%"PVDDQ_GHJ"
"1","(2550,2000)","0","mstr_symbols","I109";
;
ROOM"VDDQ_GHJ_PWR_VR"
BOM_COST"MEM_VRD_PVDDQ_CD"
HDL_POWER"PVDDQ_GHJ"
VOLTAGE"1.2V"
CDS_LIB"mstr_symbols"
BODY_TYPE"PLUMBING";
"G\NAC"1;
%"CAP"
"1","(2400,2825)","0","mstr_discrete","I110";
;
CDS_SEC"1"
ROOM"VDDQ_GHJ_PWR_VR"
SEC_TYPE"0805"
BOM_COST"MEM_VRD_PVDDQ_CD"
SEC"1"
CDS_LOCATION"C2G16"
CDS_LIB"mstr_discrete"
PACK_TYPE"0805"
VALUE"100UF"
PART_NUMBER"602433-112"
LOCATION"C2G16"
VOLTAGE"4V"
TOLERANCE"20%"
MATERIAL"X5R";
"A"
$PN"1"20;
"B"
$PN"2"21;
%"GND"
"1","(4275,1350)","0","mstr_symbols","I114";
;
HDL_POWER"GND"
BODY_TYPE"PLUMBING"
SIZE"1B"
CDS_LIB"mstr_symbols"
VOLTAGE"0"
BOM_COST"MEM_VRD_PVDDQ_CD"
ROOM"VDDQ_GHJ_PWR_VR";
"A\NAC"2;
%"VCC_CORE"
"1","(-1250,1575)","0","mstr_symbols","I120";
;
CDS_LIB"mstr_symbols"
HDL_POWER"VR_FET_SW_P12V_STBY_PVDDQ_GHJ";
"A"3;
%"GND"
"1","(-1250,825)","0","mstr_symbols","I123";
;
HDL_POWER"GND"
CDS_LIB"mstr_symbols"
SIZE"1B"
VOLTAGE"0"
BODY_TYPE"PLUMBING"
ROOM"VDDQ_GHJ_PWR_VR"
BOM_COST"MEM_VRD_PVDDQ_CD";
"A\NAC"4;
%"INDUCTOR"
"1","(-1675,1375)","0","mstr_discrete","I124";
;
CDS_SEC"1"
SEC"1"
SEC_TYPE"SM"
ROOM"VDDQ_GHJ_PWR_VR"
BOM_COST"MEM_VRD_PVDDQ_CD"
CDS_LOCATION"L1F1"
CDS_LIB"mstr_discrete"
PACK_TYPE"SM"
PART_NUMBER"D92183-020"
MATERIAL"IND"
LOCATION"L1F1"
VALUE"100NH";
"INA\NAC"
$PN"1"5;
"INB\NAC"
$PN"2"3;
%"P12V_STBY"
"1","(-2000,1575)","0","mstr_symbols","I176";
;
CDS_LIB"mstr_symbols"
SIZE"1B"
BODY_TYPE"PLUMBING"
VOLTAGE"12.0V"
HDL_POWER"P12V_STBY";
"G\NAC"5;
%"CAP"
"1","(-1950,3050)","0","mstr_discrete","I178";
;
CDS_SEC"1"
ROOM"VDDQ_GHJ_CPU1"
CDS_LOCATION"C8P31"
SEC"1"
SEC_TYPE"0805LF"
BOM_COST"MEM_VRD_PVDDQ_GHJ"
CDS_LIB"mstr_discrete"
VOLTAGE"4V"
VALUE"22UF"
LOCATION"C8P31"
PACK_TYPE"0805LF"
PART_NUMBER"C95333-002"
MATERIAL"X6S"
TOLERANCE"20%";
"A"
$PN"1"7;
"B"
$PN"2"11;
%"CAP"
"1","(-1550,3050)","0","mstr_discrete","I179";
;
CDS_SEC"1"
ROOM"VDDQ_GHJ_CPU1"
CDS_LOCATION"C2D43"
SEC"1"
BOM_COST"MEM_VRD_PVDDQ_GHJ"
SEC_TYPE"0603LF"
CDS_LIB"mstr_discrete"
LOCATION"C2D43"
VALUE"10UF"
VOLTAGE"4V"
PART_NUMBER"E15431-001"
MATERIAL"X6S"
PACK_TYPE"0603LF"
TOLERANCE"20%";
"A"
$PN"1"10;
"B"
$PN"2"6;
%"CAP"
"1","(-1200,3050)","0","mstr_discrete","I180";
;
CDS_SEC"1"
ROOM"VDDQ_GHJ_CPU1"
CDS_LOCATION"C2D41"
SEC"1"
BOM_COST"MEM_VRD_PVDDQ_GHJ"
SEC_TYPE"0603LF"
CDS_LIB"mstr_discrete"
PACK_TYPE"0603LF"
PART_NUMBER"E15431-001"
LOCATION"C2D41"
VALUE"10UF"
VOLTAGE"4V"
TOLERANCE"20%"
MATERIAL"X6S";
"A"
$PN"1"10;
"B"
$PN"2"6;
%"CAP"
"1","(-850,3050)","0","mstr_discrete","I181";
;
CDS_SEC"1"
SEC_TYPE"0603LF"
SEC"1"
BOM_COST"MEM_VRD_PVDDQ_GHJ"
ROOM"VDDQ_GHJ_CPU1"
CDS_LOCATION"C2D44"
CDS_LIB"mstr_discrete"
TOLERANCE"20%"
MATERIAL"X6S"
PACK_TYPE"0603LF"
LOCATION"C2D44"
VALUE"10UF"
VOLTAGE"4V"
PART_NUMBER"E15431-001";
"A"
$PN"1"10;
"B"
$PN"2"6;
%"GND"
"1","(-450,2675)","0","mstr_symbols","I182";
;
HDL_POWER"GND"
SIZE"1B"
CDS_LIB"mstr_symbols"
VOLTAGE"0"
BODY_TYPE"PLUMBING"
ROOM"VDDQ_ABC_PWR_VR"
BOM_COST"MEM_VRD_PVDDQ_CD";
"A\NAC"6;
%"CAP"
"1","(-450,3050)","0","mstr_discrete","I183";
;
CDS_SEC"1"
SEC_TYPE"0603LF"
BOM_COST"MEM_VRD_PVDDQ_GHJ"
SEC"1"
CDS_LOCATION"C2D42"
ROOM"VDDQ_GHJ_CPU1"
CDS_LIB"mstr_discrete"
LOCATION"C2D42"
VALUE"10UF"
VOLTAGE"4V"
PART_NUMBER"E15431-001"
PACK_TYPE"0603LF"
MATERIAL"X6S"
TOLERANCE"20%";
"A"
$PN"1"10;
"B"
$PN"2"6;
%"CAP"
"1","(-2300,3050)","0","mstr_discrete","I184";
;
CDS_SEC"1"
SEC"1"
SEC_TYPE"0805LF"
ROOM"VDDQ_GHJ_CPU1"
BOM_COST"MEM_VRD_PVDDQ_GHJ"
CDS_LOCATION"C8P30"
CDS_LIB"mstr_discrete"
VOLTAGE"4V"
PART_NUMBER"C95333-002"
VALUE"22UF"
LOCATION"C8P30"
MATERIAL"X6S"
TOLERANCE"20%"
PACK_TYPE"0805LF";
"A"
$PN"1"7;
"B"
$PN"2"11;
%"PVDDQ_GHJ"
"1","(-2300,3325)","0","mstr_symbols","I185";
;
BOM_COST"MEM_VRD_PVPP_AB"
HDL_POWER"PVDDQ_GHJ"
ROOM"VDDQ_GHJ_PWR_VR"
CDS_LIB"mstr_symbols"
VOLTAGE"1.2V"
BODY_TYPE"PLUMBING";
"G\NAC"7;
%"PVDDQ_GHJ"
"1","(2600,1250)","0","mstr_symbols","I189";
;
ROOM"VDDQ_GHJ_PWR_VR"
HDL_POWER"PVDDQ_GHJ"
BOM_COST"MEM_VRD_PVDDQ_CD"
CDS_LIB"mstr_symbols"
VOLTAGE"1.2V"
BODY_TYPE"PLUMBING";
"G\NAC"8;
%"GND"
"1","(3425,575)","0","mstr_symbols","I191";
;
SIZE"1B"
HDL_POWER"GND"
BODY_TYPE"PLUMBING"
CDS_LIB"mstr_symbols"
VOLTAGE"0"
BOM_COST"MEM_VRD_PVDDQ_CD"
ROOM"VDDQ_GHJ_PWR_VR";
"A\NAC"9;
%"CAP"
"1","(-1250,1175)","0","mstr_discrete","I192";
;
CDS_SEC"1"
SEC"1"
SEC_TYPE"1210"
CDS_LOCATION"C1G15"
CDS_LIB"mstr_discrete"
PART_NUMBER"D38464-007"
LOCATION"C1G15"
MATERIAL"X6S"
VOLTAGE"16V"
TOLERANCE"20%"
VALUE"47UF"
PACK_TYPE"1210";
"A"
$PN"1"3;
"B"
$PN"2"4;
%"CAP"
"1","(-800,1175)","0","mstr_discrete","I193";
;
CDS_SEC"1"
CDS_LOCATION"C1G12"
SEC"1"
SEC_TYPE"1210"
CDS_LIB"mstr_discrete"
LOCATION"C1G12"
PART_NUMBER"D38464-007"
VALUE"47UF"
TOLERANCE"20%"
VOLTAGE"16V"
MATERIAL"X6S"
PACK_TYPE"1210";
"A"
$PN"1"3;
"B"
$PN"2"4;
%"CAP"
"1","(-375,1175)","0","mstr_discrete","I194";
;
CDS_SEC"1"
SEC_TYPE"1210"
SEC"1"
CDS_LOCATION"C1G2"
CDS_LIB"mstr_discrete"
LOCATION"C1G2"
PART_NUMBER"D38464-007"
VALUE"47UF"
TOLERANCE"20%"
VOLTAGE"16V"
MATERIAL"X6S"
PACK_TYPE"1210";
"A"
$PN"1"3;
"B"
$PN"2"4;
%"CAP"
"1","(50,1175)","0","mstr_discrete","I195";
;
CDS_SEC"1"
SEC"1"
SEC_TYPE"1210"
CDS_LOCATION"C1G7"
CDS_LIB"mstr_discrete"
PART_NUMBER"D38464-007"
LOCATION"C1G7"
MATERIAL"X6S"
VOLTAGE"16V"
TOLERANCE"20%"
VALUE"47UF"
PACK_TYPE"1210";
"A"
$PN"1"3;
"B"
$PN"2"4;
%"CAP_A"
"1","(2600,975)","0","dev_discrete","I196";
;
SEC_TYPE"0603V"
SEC"1"
CDS_SEC"1"
CDS_LOCATION"C8T4"
CDS_LIB"dev_discrete"
VALUE"47UF"
LOCATION"C8T4"
PART_NUMBER"602433-106"
MATERIAL"X5R"
VOLTAGE"4V"
PACK_TYPE"0603V"
TOLERANCE"20%";
"B"
$PN"2"9;
"A"
$PN"1"8;
%"CAP_A"
"1","(2950,975)","0","dev_discrete","I197";
;
SEC"1"
SEC_TYPE"0603V"
CDS_SEC"1"
CDS_LOCATION"C2G8"
CDS_LIB"dev_discrete"
MATERIAL"X5R"
PACK_TYPE"0603V"
TOLERANCE"20%"
VALUE"47UF"
PART_NUMBER"602433-106"
LOCATION"C2G8"
VOLTAGE"4V";
"B"
$PN"2"9;
"A"
$PN"1"8;
%"CAP_A"
"1","(3350,975)","0","dev_discrete","I198";
;
CDS_LOCATION"C8T2"
CDS_SEC"1"
SEC_TYPE"0603V"
SEC"1"
CDS_LIB"dev_discrete"
LOCATION"C8T2"
VALUE"47UF"
PART_NUMBER"602433-106"
VOLTAGE"4V"
PACK_TYPE"0603V"
TOLERANCE"20%"
MATERIAL"X5R";
"B"
$PN"2"9;
"A"
$PN"1"8;
%"CAP_A"
"1","(2550,1725)","0","dev_discrete","I199";
;
SEC"1"
SEC_TYPE"0603V"
CDS_SEC"1"
CDS_LOCATION"C8U13"
CDS_LIB"dev_discrete"
PART_NUMBER"602433-106"
MATERIAL"X5R"
VOLTAGE"4V"
TOLERANCE"20%"
VALUE"47UF"
LOCATION"C8U13"
PACK_TYPE"0603V";
"B"
$PN"2"2;
"A"
$PN"1"1;
%"CAP_A"
"1","(2900,1725)","0","dev_discrete","I200";
;
SEC"1"
SEC_TYPE"0603V"
CDS_SEC"1"
CDS_LOCATION"C2G15"
CDS_LIB"dev_discrete"
PACK_TYPE"0603V"
PART_NUMBER"602433-106"
LOCATION"C2G15"
VALUE"47UF"
MATERIAL"X5R"
VOLTAGE"4V"
TOLERANCE"20%";
"B"
$PN"2"2;
"A"
$PN"1"1;
%"CAP_A"
"1","(3300,1725)","0","dev_discrete","I201";
;
SEC"1"
SEC_TYPE"0603V"
CDS_SEC"1"
CDS_LOCATION"C2F1"
CDS_LIB"dev_discrete"
PART_NUMBER"602433-106"
MATERIAL"X5R"
VOLTAGE"4V"
TOLERANCE"20%"
VALUE"47UF"
LOCATION"C2F1"
PACK_TYPE"0603V";
"B"
$PN"2"2;
"A"
$PN"1"1;
%"CAP_A"
"1","(3650,1725)","0","dev_discrete","I202";
;
CDS_LOCATION"C8T1"
CDS_SEC"1"
SEC_TYPE"0603V"
SEC"1"
CDS_LIB"dev_discrete"
PART_NUMBER"602433-106"
LOCATION"C8T1"
VALUE"47UF"
TOLERANCE"20%"
VOLTAGE"4V"
MATERIAL"X5R"
PACK_TYPE"0603V";
"B"
$PN"2"2;
"A"
$PN"1"1;
%"CAP_A"
"1","(4000,1725)","0","dev_discrete","I203";
;
CDS_LOCATION"C8U9"
CDS_SEC"1"
SEC_TYPE"0603V"
SEC"1"
CDS_LIB"dev_discrete"
MATERIAL"X5R"
VOLTAGE"4V"
PACK_TYPE"0603V"
TOLERANCE"20%"
VALUE"47UF"
PART_NUMBER"602433-106"
LOCATION"C8U9";
"B"
$PN"2"2;
"A"
$PN"1"1;
%"CAP_A"
"1","(4400,1725)","0","dev_discrete","I204";
;
SEC"1"
SEC_TYPE"0603V"
CDS_SEC"1"
CDS_LOCATION"C8T11"
CDS_LIB"dev_discrete"
PART_NUMBER"602433-106"
LOCATION"C8T11"
VALUE"47UF"
MATERIAL"X5R"
VOLTAGE"4V"
TOLERANCE"20%"
PACK_TYPE"0603V";
"B"
$PN"2"2;
"A"
$PN"1"1;
%"PVDDQ_GHJ"
"1","(-1550,3325)","0","mstr_symbols","I205";
;
BOM_COST"MEM_VRD_PVPP_AB"
ROOM"VDDQ_GHJ_PWR_VR"
HDL_POWER"PVDDQ_GHJ"
CDS_LIB"mstr_symbols"
BODY_TYPE"PLUMBING"
VOLTAGE"1.2V";
"G\NAC"10;
%"GND"
"1","(-1950,2700)","0","mstr_symbols","I206";
;
HDL_POWER"GND"
SIZE"1B"
VOLTAGE"0"
CDS_LIB"mstr_symbols"
BODY_TYPE"PLUMBING"
ROOM"VDDQ_ABC_PWR_VR"
BOM_COST"MEM_VRD_PVDDQ_CD";
"A\NAC"11;
%"CAP_A"
"1","(2100,250)","0","dev_discrete","I207";
;
CDS_SEC"1"
SEC_TYPE"0603V"
SEC"1"
ROOM"PVDDQ_GHJ"
CDS_LOCATION"C3G6"
CDS_LIB"dev_discrete"
VALUE"22.0UF"
PART_NUMBER"E15431-004"
LOCATION"C3G6"
VOLTAGE"4V"
TOLERANCE"20%"
PACK_TYPE"0603V"
MATERIAL"X6S";
"B"
$PN"2"13;
"A"
$PN"1"12;
%"CAP_A"
"1","(1825,250)","0","dev_discrete","I208";
;
ROOM"PVDDQ_GHJ"
SEC"1"
SEC_TYPE"0603V"
CDS_SEC"1"
CDS_LOCATION"C3G5"
CDS_LIB"dev_discrete"
VALUE"22.0UF"
PART_NUMBER"E15431-004"
LOCATION"C3G5"
VOLTAGE"4V"
TOLERANCE"20%"
PACK_TYPE"0603V"
MATERIAL"X6S";
"B"
$PN"2"13;
"A"
$PN"1"12;
%"CAP_A"
"1","(1525,250)","0","dev_discrete","I209";
;
ROOM"PVDDQ_GHJ"
SEC"1"
SEC_TYPE"0603V"
CDS_SEC"1"
CDS_LOCATION"C2G14"
CDS_LIB"dev_discrete"
PART_NUMBER"E15431-004"
MATERIAL"X6S"
VOLTAGE"4V"
PACK_TYPE"0603V"
TOLERANCE"20%"
VALUE"22.0UF"
LOCATION"C2G14";
"B"
$PN"2"13;
"A"
$PN"1"12;
%"CAP_A"
"1","(1225,250)","0","dev_discrete","I210";
;
ROOM"PVDDQ_GHJ"
CDS_SEC"1"
SEC_TYPE"0603V"
SEC"1"
CDS_LOCATION"C2G13"
CDS_LIB"dev_discrete"
PART_NUMBER"E15431-004"
MATERIAL"X6S"
VOLTAGE"4V"
PACK_TYPE"0603V"
TOLERANCE"20%"
VALUE"22.0UF"
LOCATION"C2G13";
"B"
$PN"2"13;
"A"
$PN"1"12;
%"CAP_A"
"1","(950,250)","0","dev_discrete","I211";
;
ROOM"PVDDQ_GHJ"
CDS_SEC"1"
SEC_TYPE"0603V"
SEC"1"
CDS_LOCATION"C3G2"
CDS_LIB"dev_discrete"
MATERIAL"X6S"
VOLTAGE"4V"
PACK_TYPE"0603V"
TOLERANCE"20%"
VALUE"22.0UF"
PART_NUMBER"E15431-004"
LOCATION"C3G2";
"B"
$PN"2"13;
"A"
$PN"1"12;
%"CAP_A"
"1","(675,250)","0","dev_discrete","I212";
;
ROOM"PVDDQ_GHJ"
CDS_SEC"1"
SEC_TYPE"0603V"
SEC"1"
CDS_LOCATION"C3G1"
CDS_LIB"dev_discrete"
MATERIAL"X6S"
VOLTAGE"4V"
PACK_TYPE"0603V"
TOLERANCE"20%"
VALUE"22.0UF"
PART_NUMBER"E15431-004"
LOCATION"C3G1";
"B"
$PN"2"13;
"A"
$PN"1"12;
%"CAP_A"
"1","(375,250)","0","dev_discrete","I213";
;
ROOM"PVDDQ_GHJ"
SEC_TYPE"0603V"
SEC"1"
CDS_LOCATION"C2G6"
CDS_SEC"1"
CDS_LIB"dev_discrete"
MATERIAL"X6S"
PACK_TYPE"0603V"
TOLERANCE"20%"
VALUE"22.0UF"
PART_NUMBER"E15431-004"
LOCATION"C2G6"
VOLTAGE"4V";
"B"
$PN"2"13;
"A"
$PN"1"12;
%"CAP_A"
"1","(75,250)","0","dev_discrete","I214";
;
ROOM"PVDDQ_GHJ"
SEC"1"
SEC_TYPE"0603V"
CDS_SEC"1"
CDS_LOCATION"C2G5"
CDS_LIB"dev_discrete"
PACK_TYPE"0603V"
VALUE"22.0UF"
PART_NUMBER"E15431-004"
LOCATION"C2G5"
VOLTAGE"4V"
TOLERANCE"20%"
MATERIAL"X6S";
"B"
$PN"2"13;
"A"
$PN"1"12;
%"CAP_A"
"1","(-250,250)","0","dev_discrete","I215";
;
CDS_LOCATION"C2G4"
CDS_SEC"1"
SEC_TYPE"0603V"
SEC"1"
ROOM"PVDDQ_GHJ"
CDS_LIB"dev_discrete"
PART_NUMBER"E15431-004"
VALUE"22.0UF"
LOCATION"C2G4"
VOLTAGE"4V"
TOLERANCE"20%"
PACK_TYPE"0603V"
MATERIAL"X6S";
"B"
$PN"2"13;
"A"
$PN"1"12;
%"CAP_A"
"1","(-525,250)","0","dev_discrete","I216";
;
ROOM"PVDDQ_GHJ"
SEC"1"
SEC_TYPE"0603V"
CDS_SEC"1"
CDS_LOCATION"C2G3"
CDS_LIB"dev_discrete"
LOCATION"C2G3"
PART_NUMBER"E15431-004"
MATERIAL"X6S"
VOLTAGE"4V"
PACK_TYPE"0603V"
TOLERANCE"20%"
VALUE"22.0UF";
"B"
$PN"2"13;
"A"
$PN"1"12;
%"CAP_A"
"1","(-825,250)","0","dev_discrete","I217";
;
ROOM"PVDDQ_GHJ"
CDS_SEC"1"
SEC_TYPE"0603V"
SEC"1"
CDS_LOCATION"C2G2"
CDS_LIB"dev_discrete"
PART_NUMBER"E15431-004"
MATERIAL"X6S"
VOLTAGE"4V"
PACK_TYPE"0603V"
TOLERANCE"20%"
VALUE"22.0UF"
LOCATION"C2G2";
"B"
$PN"2"13;
"A"
$PN"1"12;
%"CAP_A"
"1","(-1125,250)","0","dev_discrete","I218";
;
ROOM"PVDDQ_ABC"
CDS_SEC"1"
SEC_TYPE"0603V"
SEC"1"
CDS_LOCATION"C2G9"
CDS_LIB"dev_discrete"
MATERIAL"X6S"
VOLTAGE"4V"
PACK_TYPE"0603V"
TOLERANCE"20%"
VALUE"22.0UF"
PART_NUMBER"E15431-004"
LOCATION"C2G9";
"B"
$PN"2"13;
"A"
$PN"1"12;
%"CAP_A"
"1","(-1400,250)","0","dev_discrete","I219";
;
ROOM"PVDDQ_GHJ"
SEC_TYPE"0603V"
SEC"1"
CDS_LOCATION"C2G1"
CDS_SEC"1"
CDS_LIB"dev_discrete"
MATERIAL"X6S"
PACK_TYPE"0603V"
TOLERANCE"20%"
VALUE"22.0UF"
PART_NUMBER"E15431-004"
LOCATION"C2G1"
VOLTAGE"4V";
"B"
$PN"2"13;
"A"
$PN"1"12;
%"CAP_A"
"1","(-1675,250)","0","dev_discrete","I220";
;
CDS_LOCATION"C2G12"
CDS_SEC"1"
SEC_TYPE"0603V"
SEC"1"
ROOM"PVDDQ_GHJ"
CDS_LIB"dev_discrete"
PACK_TYPE"0603V"
VALUE"22.0UF"
PART_NUMBER"E15431-004"
LOCATION"C2G12"
VOLTAGE"4V"
TOLERANCE"20%"
MATERIAL"X6S";
"B"
$PN"2"13;
"A"
$PN"1"12;
%"CAP_A"
"1","(-1975,250)","0","dev_discrete","I221";
;
ROOM"PVDDQ_GHJ"
SEC"1"
SEC_TYPE"0603V"
CDS_SEC"1"
CDS_LOCATION"C2G11"
CDS_LIB"dev_discrete"
PACK_TYPE"0603V"
VALUE"22.0UF"
PART_NUMBER"E15431-004"
LOCATION"C2G11"
VOLTAGE"4V"
TOLERANCE"20%"
MATERIAL"X6S";
"B"
$PN"2"13;
"A"
$PN"1"12;
%"PVDDQ_GHJ"
"1","(-2275,500)","0","mstr_symbols","I222";
;
HDL_POWER"PVDDQ_GHJ"
CDS_LIB"mstr_symbols"
BODY_TYPE"PLUMBING"
VOLTAGE"1.2V";
"G\NAC"12;
%"CAP_A"
"1","(-2275,250)","0","dev_discrete","I223";
;
SEC_TYPE"0603V"
CDS_SEC"1"
SEC"1"
ROOM"PVDDQ_GHJ"
CDS_LOCATION"C2G10"
CDS_LIB"dev_discrete"
PART_NUMBER"E15431-004"
VALUE"22.0UF"
LOCATION"C2G10"
VOLTAGE"4V"
TOLERANCE"20%"
PACK_TYPE"0603V"
MATERIAL"X6S";
"B"
$PN"2"13;
"A"
$PN"1"12;
%"GND"
"1","(-2275,-25)","0","mstr_symbols","I224";
;
HDL_POWER"GND"
ROOM"VDDQ_ABC_PWR_VR"
BOM_COST"PROC_VRD_VCCIN_CPU0"
CDS_LIB"mstr_symbols"
VOLTAGE"0"
SIZE"1B"
BODY_TYPE"PLUMBING";
"A\NAC"13;
%"CAP_A"
"1","(2125,-450)","0","dev_discrete","I225";
;
SEC_TYPE"0603V"
ROOM"PVDDQ_GHJ"
CDS_LOCATION"C8U4"
CDS_LIB"dev_discrete"
CDS_SEC"1"
SEC"1"
VALUE"22.0UF"
VOLTAGE"4V"
TOLERANCE"20%"
LOCATION"C8U4"
PART_NUMBER"E15431-004"
PACK_TYPE"0603V"
MATERIAL"X6S";
"B"
$PN"2"15;
"A"
$PN"1"14;
%"CAP_A"
"1","(1850,-450)","0","dev_discrete","I226";
;
SEC_TYPE"0603V"
ROOM"PVDDQ_GHJ"
CDS_LOCATION"C8T10"
CDS_SEC"1"
SEC"1"
CDS_LIB"dev_discrete"
LOCATION"C8T10"
VALUE"22.0UF"
PART_NUMBER"E15431-004"
VOLTAGE"4V"
TOLERANCE"20%"
PACK_TYPE"0603V"
MATERIAL"X6S";
"B"
$PN"2"15;
"A"
$PN"1"14;
%"CAP_A"
"1","(1550,-450)","0","dev_discrete","I227";
;
SEC_TYPE"0603V"
ROOM"PVDDQ_GHJ"
CDS_LOCATION"C8T9"
CDS_SEC"1"
SEC"1"
CDS_LIB"dev_discrete"
LOCATION"C8T9"
VALUE"22.0UF"
TOLERANCE"20%"
VOLTAGE"4V"
PART_NUMBER"E15431-004"
PACK_TYPE"0603V"
MATERIAL"X6S";
"B"
$PN"2"15;
"A"
$PN"1"14;
%"CAP_A"
"1","(1250,-450)","0","dev_discrete","I228";
;
ROOM"PVDDQ_GHJ"
SEC"1"
SEC_TYPE"0603V"
CDS_SEC"1"
CDS_LOCATION"C8U5"
CDS_LIB"dev_discrete"
PART_NUMBER"E15431-004"
VOLTAGE"4V"
TOLERANCE"20%"
VALUE"22.0UF"
LOCATION"C8U5"
MATERIAL"X6S"
PACK_TYPE"0603V";
"B"
$PN"2"15;
"A"
$PN"1"14;
%"CAP_A"
"1","(975,-450)","0","dev_discrete","I229";
;
ROOM"PVDDQ_GHJ"
SEC_TYPE"0603V"
CDS_LOCATION"C8T8"
CDS_SEC"1"
SEC"1"
CDS_LIB"dev_discrete"
VALUE"22.0UF"
VOLTAGE"4V"
TOLERANCE"20%"
LOCATION"C8T8"
PART_NUMBER"E15431-004"
PACK_TYPE"0603V"
MATERIAL"X6S";
"B"
$PN"2"15;
"A"
$PN"1"14;
%"CAP_A"
"1","(700,-450)","0","dev_discrete","I230";
;
SEC_TYPE"0603V"
ROOM"PVDDQ_GHJ"
CDS_SEC"1"
CDS_LOCATION"C8T7"
SEC"1"
CDS_LIB"dev_discrete"
PART_NUMBER"E15431-004"
LOCATION"C8T7"
VALUE"22.0UF"
TOLERANCE"20%"
VOLTAGE"4V"
PACK_TYPE"0603V"
MATERIAL"X6S";
"B"
$PN"2"15;
"A"
$PN"1"14;
%"CAP_A"
"1","(400,-450)","0","dev_discrete","I231";
;
SEC_TYPE"0603V"
ROOM"PVDDQ_GHJ"
CDS_LOCATION"C8T6"
CDS_SEC"1"
SEC"1"
CDS_LIB"dev_discrete"
MATERIAL"X6S"
PACK_TYPE"0603V"
TOLERANCE"20%"
VALUE"22.0UF"
PART_NUMBER"E15431-004"
LOCATION"C8T6"
VOLTAGE"4V";
"B"
$PN"2"15;
"A"
$PN"1"14;
%"CAP_A"
"1","(100,-450)","0","dev_discrete","I232";
;
SEC_TYPE"0603V"
SEC"1"
ROOM"PVDDQ_GHJ"
CDS_SEC"1"
CDS_LOCATION"C8U6"
CDS_LIB"dev_discrete"
LOCATION"C8U6"
VALUE"22.0UF"
TOLERANCE"20%"
VOLTAGE"4V"
PART_NUMBER"E15431-004"
PACK_TYPE"0603V"
MATERIAL"X6S";
"B"
$PN"2"15;
"A"
$PN"1"14;
%"CAP_A"
"1","(-225,-450)","0","dev_discrete","I233";
;
SEC_TYPE"0603V"
ROOM"PVDDQ_GHJ"
CDS_LOCATION"C8T5"
CDS_SEC"1"
SEC"1"
CDS_LIB"dev_discrete"
PART_NUMBER"E15431-004"
VOLTAGE"4V"
TOLERANCE"20%"
VALUE"22.0UF"
LOCATION"C8T5"
PACK_TYPE"0603V"
MATERIAL"X6S";
"B"
$PN"2"15;
"A"
$PN"1"14;
%"CAP_A"
"1","(-500,-450)","0","dev_discrete","I234";
;
SEC_TYPE"0603V"
ROOM"PVDDQ_GHJ"
CDS_LOCATION"C7T5"
CDS_SEC"1"
SEC"1"
CDS_LIB"dev_discrete"
LOCATION"C7T5"
VALUE"22.0UF"
TOLERANCE"20%"
VOLTAGE"4V"
PART_NUMBER"E15431-004"
PACK_TYPE"0603V"
MATERIAL"X6S";
"B"
$PN"2"15;
"A"
$PN"1"14;
%"CAP_A"
"1","(-800,-450)","0","dev_discrete","I235";
;
SEC"1"
ROOM"PVDDQ_GHJ"
CDS_LOCATION"C7T4"
CDS_SEC"1"
SEC_TYPE"0603V"
CDS_LIB"dev_discrete"
PART_NUMBER"E15431-004"
VOLTAGE"4V"
TOLERANCE"20%"
VALUE"22.0UF"
LOCATION"C7T4"
PACK_TYPE"0603V"
MATERIAL"X6S";
"B"
$PN"2"15;
"A"
$PN"1"14;
%"CAP_A"
"1","(-1100,-450)","0","dev_discrete","I236";
;
SEC_TYPE"0603V"
SEC"1"
ROOM"PVDDQ_ABC"
CDS_LOCATION"C8U3"
CDS_SEC"1"
CDS_LIB"dev_discrete"
MATERIAL"X6S"
VOLTAGE"4V"
PACK_TYPE"0603V"
TOLERANCE"20%"
VALUE"22.0UF"
PART_NUMBER"E15431-004"
LOCATION"C8U3";
"B"
$PN"2"15;
"A"
$PN"1"14;
%"CAP_A"
"1","(-1375,-450)","0","dev_discrete","I237";
;
SEC_TYPE"0603V"
ROOM"PVDDQ_GHJ"
CDS_SEC"1"
CDS_LOCATION"C7U1"
SEC"1"
CDS_LIB"dev_discrete"
LOCATION"C7U1"
VALUE"22.0UF"
TOLERANCE"20%"
VOLTAGE"4V"
PART_NUMBER"E15431-004"
PACK_TYPE"0603V"
MATERIAL"X6S";
"B"
$PN"2"15;
"A"
$PN"1"14;
%"CAP_A"
"1","(-1650,-450)","0","dev_discrete","I238";
;
SEC_TYPE"0603V"
ROOM"PVDDQ_GHJ"
CDS_LOCATION"C7U2"
CDS_SEC"1"
SEC"1"
CDS_LIB"dev_discrete"
MATERIAL"X6S"
PACK_TYPE"0603V"
TOLERANCE"20%"
VALUE"22.0UF"
PART_NUMBER"E15431-004"
LOCATION"C7U2"
VOLTAGE"4V";
"B"
$PN"2"15;
"A"
$PN"1"14;
%"CAP_A"
"1","(-1950,-450)","0","dev_discrete","I239";
;
SEC_TYPE"0603V"
ROOM"PVDDQ_GHJ"
SEC"1"
CDS_LOCATION"C8U2"
CDS_SEC"1"
CDS_LIB"dev_discrete"
LOCATION"C8U2"
VALUE"22.0UF"
TOLERANCE"20%"
VOLTAGE"4V"
PART_NUMBER"E15431-004"
PACK_TYPE"0603V"
MATERIAL"X6S";
"B"
$PN"2"15;
"A"
$PN"1"14;
%"PVDDQ_GHJ"
"1","(-2250,-200)","0","mstr_symbols","I240";
;
HDL_POWER"PVDDQ_GHJ"
BODY_TYPE"PLUMBING"
CDS_LIB"mstr_symbols"
VOLTAGE"1.2V";
"G\NAC"14;
%"CAP_A"
"1","(-2250,-450)","0","dev_discrete","I241";
;
ROOM"PVDDQ_GHJ"
SEC"1"
SEC_TYPE"0603V"
CDS_SEC"1"
CDS_LOCATION"C8U7"
CDS_LIB"dev_discrete"
VALUE"22.0UF"
PART_NUMBER"E15431-004"
LOCATION"C8U7"
TOLERANCE"20%"
VOLTAGE"4V"
PACK_TYPE"0603V"
MATERIAL"X6S";
"B"
$PN"2"15;
"A"
$PN"1"14;
%"GND"
"1","(-2250,-725)","0","mstr_symbols","I242";
;
HDL_POWER"GND"
CDS_LIB"mstr_symbols"
VOLTAGE"0"
BODY_TYPE"PLUMBING"
SIZE"1B"
ROOM"VDDQ_ABC_PWR_VR"
BOM_COST"PROC_VRD_VCCIN_CPU0";
"A\NAC"15;
%"SHUNT"
"1","(-250,2325)","0","mstr_misc","I243";
;
CDS_SEC"1"
CDS_LOCATION"SH7U1"
CDS_LIB"mstr_misc"
SEC_TYPE"SH0201"
SEC"1"
MATERIAL"EMPTY"
PACK_TYPE"SH0201"
PIN_SHORT"A:B"
PART_NUMBER"N_A"
LOCATION"SH7U1";
"A"
$PN"1"23;
"B"
$PN"2"17;
%"SHUNT"
"1","(-275,1875)","0","mstr_misc","I244";
;
CDS_SEC"1"
CDS_LOCATION"SH7U2"
SEC_TYPE"SH0201"
SEC"1"
CDS_LIB"mstr_misc"
PIN_SHORT"A:B"
PACK_TYPE"SH0201"
MATERIAL"EMPTY"
LOCATION"SH7U2"
PART_NUMBER"N_A";
"A"
$PN"1"22;
"B"
$PN"2"16;
%"RES"
"2","(4325,-75)","0","mstr_discrete","I58";
;
ROOM"VDDQ_GHJ_PWR_VR"
CDS_LOCATION"R1G20"
$SEC"1"
CDS_SEC"1"
BOM_COST"MEM_VRD_PVPP_AB"
CDS_LIB"mstr_discrete"
LOCATION"R1G20"
VALUE"120.0"
PART_NUMBER"G22026-003"
TOLERANCE"1%"
PACK_TYPE"0603"
MATERIAL"CHIP"
WATTAGE"1/10W";
"A"
$PN"1"18;
"B"
$PN"2"19;
%"GND"
"1","(100,1750)","0","mstr_symbols","I65";
;
HDL_POWER"GND"
BODY_TYPE"PLUMBING"
SIZE"1B"
CDS_LIB"mstr_symbols"
VOLTAGE"0"
BOM_COST"MEM_VRD_PVPP_AB"
ROOM"VDDQ_GHJ_PWR_VR";
"A\NAC"16;
%"PVDDQ_GHJ"
"1","(100,2450)","0","mstr_symbols","I73";
;
ROOM"VDDQ_GHJ_PWR_VR"
BOM_COST"MEM_VRD_PVPP_AB"
HDL_POWER"PVDDQ_GHJ"
BODY_TYPE"PLUMBING"
CDS_LIB"mstr_symbols"
VOLTAGE"1.2V";
"G\NAC"17;
%"RES"
"2","(-650,2075)","0","mstr_discrete","I74";
;
CDS_SEC"1"
SEC"1"
SEC_TYPE"0402"
ROOM"VDDQ_GHJ_PWR_VR"
CDS_LOCATION"R7U2"
CDS_LIB"mstr_discrete"
VALUE"100.0"
WATTAGE"1/16W"
PART_NUMBER"G21796-017"
LOCATION"R7U2"
TOLERANCE"1%"
PACK_TYPE"0402"
MATERIAL"EMPTY";
"A"
$PN"1"23;
"B"
$PN"2"22;
%"CAPP"
"1","(2700,-75)","0","mstr_discrete","I75";
;
CDS_SEC"1"
SEC_TYPE"3018"
SEC"1"
ROOM"VDDQ_GHJ_PWR_VR"
CDS_LOCATION"C9T5"
CDS_LIB"mstr_discrete"
LOCATION"C9T5"
VALUE"470UF"
MATERIAL"ALUM"
VOLTAGE"2.5V"
PACK_TYPE"3018"
TOLERANCE"20%"
PART_NUMBER"699013-049";
"B"
$PN"2"19;
"A"
$PN"1"18;
%"CAPP"
"1","(3125,-75)","0","mstr_discrete","I76";
;
CDS_SEC"1"
SEC_TYPE"3018"
SEC"1"
CDS_LOCATION"C9U2"
ROOM"VDDQ_GHJ_PWR_VR"
CDS_LIB"mstr_discrete"
LOCATION"C9U2"
VALUE"470UF"
PART_NUMBER"699013-049"
MATERIAL"ALUM"
VOLTAGE"2.5V"
PACK_TYPE"3018"
TOLERANCE"20%";
"B"
$PN"2"19;
"A"
$PN"1"18;
%"CAPP"
"1","(3550,-75)","0","mstr_discrete","I77";
;
CDS_SEC"1"
ROOM"VDDQ_GHJ_PWR_VR"
CDS_LOCATION"C9U9"
SEC"1"
SEC_TYPE"3018"
CDS_LIB"mstr_discrete"
LOCATION"C9U9"
VALUE"470UF"
PART_NUMBER"699013-049"
MATERIAL"ALUM"
VOLTAGE"2.5V"
PACK_TYPE"3018"
TOLERANCE"20%";
"B"
$PN"2"19;
"A"
$PN"1"18;
%"CAPP"
"1","(3950,-100)","0","mstr_discrete","I78";
;
CDS_SEC"1"
ROOM"VDDQ_GHJ_PWR_VR"
SEC"1"
SEC_TYPE"3018"
CDS_LOCATION"C9U5"
CDS_LIB"mstr_discrete"
LOCATION"C9U5"
MATERIAL"ALUM"
VOLTAGE"2.5V"
PACK_TYPE"3018"
VALUE"470UF"
PART_NUMBER"699013-049"
TOLERANCE"20%";
"B"
$PN"2"19;
"A"
$PN"1"18;
%"PVDDQ_GHJ"
"1","(2700,225)","0","mstr_symbols","I80";
;
ROOM"VDDQ_GHJ_PWR_VR"
HDL_POWER"PVDDQ_GHJ"
BOM_COST"MEM_VRD_PVPP_AB"
CDS_LIB"mstr_symbols"
VOLTAGE"1.2V"
BODY_TYPE"PLUMBING";
"G\NAC"18;
%"GND"
"1","(2700,-500)","0","mstr_symbols","I81";
;
VOLTAGE"0"
CDS_LIB"mstr_symbols"
HDL_POWER"GND"
BODY_TYPE"PLUMBING"
SIZE"1B"
BOM_COST"MEM_VRD_PVPP_AB";
"A\NAC"19;
%"CAP"
"1","(5000,2825)","0","mstr_discrete","I82";
;
CDS_SEC"1"
ROOM"VDDQ_GHJ_PWR_VR"
SEC_TYPE"0805"
BOM_COST"MEM_VRD_PVDDQ_CD"
SEC"1"
CDS_LOCATION"C8U1"
CDS_LIB"mstr_discrete"
MATERIAL"X5R"
PACK_TYPE"0805"
TOLERANCE"20%"
VALUE"100UF"
PART_NUMBER"602433-112"
LOCATION"C8U1"
VOLTAGE"4V";
"A"
$PN"1"20;
"B"
$PN"2"21;
%"CAP"
"1","(4600,2825)","0","mstr_discrete","I83";
;
CDS_SEC"1"
ROOM"VDDQ_GHJ_PWR_VR"
CDS_LOCATION"C8U8"
SEC"1"
BOM_COST"MEM_VRD_PVDDQ_CD"
SEC_TYPE"0805"
CDS_LIB"mstr_discrete"
PART_NUMBER"602433-112"
MATERIAL"X5R"
VOLTAGE"4V"
PACK_TYPE"0805"
TOLERANCE"20%"
VALUE"100UF"
LOCATION"C8U8";
"A"
$PN"1"20;
"B"
$PN"2"21;
%"CAP"
"1","(4250,2825)","0","mstr_discrete","I88";
;
CDS_SEC"1"
ROOM"VDDQ_GHJ_PWR_VR"
SEC_TYPE"0805"
BOM_COST"MEM_VRD_PVDDQ_CD"
SEC"1"
CDS_LOCATION"C8U12"
CDS_LIB"mstr_discrete"
MATERIAL"X5R"
VOLTAGE"4V"
PACK_TYPE"0805"
TOLERANCE"20%"
VALUE"100UF"
PART_NUMBER"602433-112"
LOCATION"C8U12";
"A"
$PN"1"20;
"B"
$PN"2"21;
%"CAP"
"1","(3850,2825)","0","mstr_discrete","I89";
;
CDS_SEC"1"
ROOM"VDDQ_GHJ_PWR_VR"
SEC"1"
SEC_TYPE"0805"
BOM_COST"MEM_VRD_PVDDQ_CD"
CDS_LOCATION"C8U11"
CDS_LIB"mstr_discrete"
PART_NUMBER"602433-112"
VALUE"100UF"
LOCATION"C8U11"
VOLTAGE"4V"
TOLERANCE"20%"
PACK_TYPE"0805"
MATERIAL"X5R";
"A"
$PN"1"20;
"B"
$PN"2"21;
%"CAP"
"1","(3500,2825)","0","mstr_discrete","I90";
;
CDS_SEC"1"
ROOM"VDDQ_GHJ_PWR_VR"
BOM_COST"MEM_VRD_PVDDQ_CD"
SEC_TYPE"0805"
SEC"1"
CDS_LOCATION"C7T1"
CDS_LIB"mstr_discrete"
MATERIAL"X5R"
VOLTAGE"4V"
PACK_TYPE"0805"
TOLERANCE"20%"
VALUE"100UF"
PART_NUMBER"602433-112"
LOCATION"C7T1";
"A"
$PN"1"20;
"B"
$PN"2"21;
%"CAP"
"1","(3150,2825)","0","mstr_discrete","I91";
;
CDS_SEC"1"
BOM_COST"MEM_VRD_PVDDQ_CD"
SEC_TYPE"0805"
SEC"1"
CDS_LOCATION"C7U7"
ROOM"VDDQ_GHJ_PWR_VR"
CDS_LIB"mstr_discrete"
VALUE"100UF"
PART_NUMBER"602433-112"
VOLTAGE"4V"
LOCATION"C7U7"
TOLERANCE"20%"
PACK_TYPE"0805"
MATERIAL"X5R";
"A"
$PN"1"20;
"B"
$PN"2"21;
%"CAP"
"1","(2750,2825)","0","mstr_discrete","I92";
;
CDS_SEC"1"
ROOM"VDDQ_GHJ_PWR_VR"
BOM_COST"MEM_VRD_PVDDQ_CD"
SEC_TYPE"0805"
SEC"1"
CDS_LOCATION"C2G7"
CDS_LIB"mstr_discrete"
PART_NUMBER"602433-112"
MATERIAL"X5R"
VOLTAGE"4V"
PACK_TYPE"0805"
TOLERANCE"20%"
VALUE"100UF"
LOCATION"C2G7";
"A"
$PN"1"20;
"B"
$PN"2"21;
%"PVDDQ_GHJ"
"1","(2400,3100)","0","mstr_symbols","I93";
;
HDL_POWER"PVDDQ_GHJ"
ROOM"VDDQ_GHJ_PWR_VR"
CDS_LIB"mstr_symbols"
BOM_COST"MEM_VRD_PVDDQ_CD"
VOLTAGE"1.2V"
BODY_TYPE"PLUMBING";
"G\NAC"20;
%"GND"
"1","(4125,2450)","0","mstr_symbols","I94";
;
HDL_POWER"GND"
SIZE"1B"
CDS_LIB"mstr_symbols"
VOLTAGE"0"
BOM_COST"MEM_VRD_PVDDQ_CD"
BODY_TYPE"PLUMBING"
ROOM"VDDQ_GHJ_PWR_VR";
"A\NAC"21;
END.
